(kicad_pcb
	(version 20260206)
	(generator "pcbnew")
	(generator_version "10.0")
	(general
		(thickness 1.6)
		(legacy_teardrops no)
	)
	(paper "A4")
	(title_block
		(title "timecard-production-celestica-r4006 — R4006-B0001-02_R01.brd")
		(comment 1 "Time Appliance Project (Time Card) / footprints 956-960 of 1113")
	)
	(layers
		(0 "F.Cu" signal "TOP")
		(4 "In1.Cu" signal "L02_GND1")
		(6 "In2.Cu" signal "L03_SIG1")
		(8 "In3.Cu" signal "L04_GND2")
		(10 "In4.Cu" signal "L05_VCC1")
		(12 "In5.Cu" signal "L06_VCC2")
		(14 "In6.Cu" signal "L07_GND3")
		(16 "In7.Cu" signal "L08_SIG2")
		(18 "In8.Cu" signal "L09_GND4")
		(2 "B.Cu" signal "BOTTOM")
		(9 "F.Adhes" user "F.Adhesive")
		(11 "B.Adhes" user "B.Adhesive")
		(13 "F.Paste" user "Package Geometry/Pastemask Top")
		(15 "B.Paste" user "Package Geometry/Pastemask Bottom")
		(5 "F.SilkS" user "Ref Des/Silkscreen Top")
		(7 "B.SilkS" user "Ref Des/Silkscreen Bottom")
		(1 "F.Mask" user "Board Geometry/Soldermask Top")
		(3 "B.Mask" user "Board Geometry/Soldermask Bottom")
		(17 "Dwgs.User" user "User.Drawings")
		(19 "Cmts.User" user "User.Comments")
		(21 "Eco1.User" user "User.Eco1")
		(23 "Eco2.User" user "User.Eco2")
		(25 "Edge.Cuts" user "Board Geometry/Outline")
		(27 "Margin" user)
		(31 "F.CrtYd" user "Package Geometry/Place Bound Top")
		(29 "B.CrtYd" user "Package Geometry/Place Bound Bottom")
		(35 "F.Fab" user "Ref Des/Assembly Top")
		(33 "B.Fab" user "Ref Des/Assembly Bottom")
	)
	(footprint ""
		(layer "B.Cu")
		(at 144.78 -59.563 90)
		(property "Reference" "R252"
			(at 0.889 3.13563 270)
			(unlocked yes)
			(layer "B.SilkS")
			(effects
				(font
					(size 0.7874 0.5842)
					(thickness 0.1524)
				)
				(justify mirror)
			)
		)
		(property "Value" "VAL*"
			(at 0.0254 2.524506 90)
			(unlocked yes)
			(layer "B.Fab")
			(hide yes)
			(effects
				(font
					(size 0.7874 0.5842)
					(thickness 0.1524)
				)
				(justify mirror)
			)
		)
		(property "Device Type" "RESISTOR-G156-100R0-J0,0OHM,-"
			(at 0 1.610106 90)
			(unlocked yes)
			(layer "B.Fab")
			(hide yes)
			(effects
				(font
					(size 0.7874 0.5842)
					(thickness 0.1524)
				)
				(justify mirror)
			)
		)
		(property "User Part Number" "PARTNUM*"
			(at 0.0254 4.505706 90)
			(unlocked yes)
			(layer "Cmts.User")
			(hide yes)
			(effects
				(font
					(size 0.7874 0.5842)
					(thickness 0.1524)
				)
				(justify mirror)
			)
		)
		(property "Tolerance" "TOL*"
			(at 0.0254 3.464306 90)
			(unlocked yes)
			(layer "Cmts.User")
			(hide yes)
			(effects
				(font
					(size 0.7874 0.5842)
					(thickness 0.1524)
				)
				(justify mirror)
			)
		)
		(duplicate_pad_numbers_are_jumpers no)
		(fp_line
			(start 1.3208 -0.7112)
			(end -1.3208 -0.7112)
			(stroke
				(width 0.1)
				(type default)
			)
			(layer "B.SilkS")
		)
		(fp_line
			(start -1.3208 -0.7112)
			(end -1.3208 0.7112)
			(stroke
				(width 0.1)
				(type default)
			)
			(layer "B.SilkS")
		)
		(fp_line
			(start 1.3208 0.7112)
			(end 1.3208 -0.7112)
			(stroke
				(width 0.1)
				(type default)
			)
			(layer "B.SilkS")
		)
		(fp_line
			(start -1.3208 0.7112)
			(end 1.3208 0.7112)
			(stroke
				(width 0.1)
				(type default)
			)
			(layer "B.SilkS")
		)
		(fp_rect
			(start -1.3208 -0.7112)
			(end 1.3208 0.7112)
			(stroke
				(width 0)
				(type default)
			)
			(fill no)
			(layer "B.CrtYd")
		)
		(fp_line
			(start 0.8128 -0.4572)
			(end -0.8128 -0.4572)
			(stroke
				(width 0.1)
				(type default)
			)
			(layer "B.Fab")
		)
		(fp_line
			(start -0.8128 -0.4572)
			(end -0.8128 0.4572)
			(stroke
				(width 0.1)
				(type default)
			)
			(layer "B.Fab")
		)
		(fp_line
			(start 0.8128 0.4572)
			(end 0.8128 -0.4572)
			(stroke
				(width 0.1)
				(type default)
			)
			(layer "B.Fab")
		)
		(fp_line
			(start -0.8128 0.4572)
			(end 0.8128 0.4572)
			(stroke
				(width 0.1)
				(type default)
			)
			(layer "B.Fab")
		)
		(pad "1" smd rect
			(at 0.6858 0 270)
			(size 0.762 0.8636)
			(layers "B.Cu" "B.Mask" "B.Paste")
			(net "XP1R0V_AGND")
		)
		(pad "2" smd rect
			(at -0.6858 0 270)
			(size 0.762 0.8636)
			(layers "B.Cu" "B.Mask" "B.Paste")
			(net "XP1R0V_FB_R_TO_AGND")
		)
		(zone
			(layer "B.Cu")
			(hatch none 0.5)
			(connect_pads
				(clearance 0)
			)
			(min_thickness 0.25)
			(keepout
				(tracks allowed)
				(vias not_allowed)
				(pads allowed)
				(copperpour not_allowed)
				(footprints allowed)
			)
			(placement
				(enabled no)
				(sheetname "")
			)
			(fill
				(thermal_gap 0.5)
				(thermal_bridge_width 0.5)
				(island_removal_mode 0)
			)
			(polygon
				(pts
					(xy 144.3228 -59.4106) (xy 145.2372 -59.4106) (xy 145.2372 -59.7154) (xy 144.3228 -59.7154)
				)
			)
		)
	)
	(footprint ""
		(layer "B.Cu")
		(at 22.606 -88.9 180)
		(property "Reference" "R469"
			(at -1.016 -3.59537 0)
			(unlocked yes)
			(layer "B.SilkS")
			(effects
				(font
					(size 0.7874 0.5842)
					(thickness 0.1524)
				)
				(justify mirror)
			)
		)
		(property "Value" "VAL*"
			(at -0.02032 2.13233 180)
			(unlocked yes)
			(layer "B.Fab")
			(hide yes)
			(effects
				(font
					(size 0.7874 0.5842)
					(thickness 0.1524)
				)
				(justify mirror)
			)
		)
		(property "Tolerance" "TOL*"
			(at -0.044704 3.05435 180)
			(unlocked yes)
			(layer "Cmts.User")
			(hide yes)
			(effects
				(font
					(size 0.7874 0.5842)
					(thickness 0.1524)
				)
				(justify mirror)
			)
		)
		(property "User Part Number" "PARTNUM*"
			(at -0.02032 4.024884 180)
			(unlocked yes)
			(layer "Cmts.User")
			(hide yes)
			(effects
				(font
					(size 0.7874 0.5842)
					(thickness 0.1524)
				)
				(justify mirror)
			)
		)
		(property "Device Type" "RESISTOR-G155-133R0-01,33OHM,1%"
			(at -0.008382 1.210564 180)
			(unlocked yes)
			(layer "B.Fab")
			(hide yes)
			(effects
				(font
					(size 0.7874 0.5842)
					(thickness 0.1524)
				)
				(justify mirror)
			)
		)
		(duplicate_pad_numbers_are_jumpers no)
		(fp_line
			(start 1.143 0.5588)
			(end -1.143 0.5588)
			(stroke
				(width 0.1)
				(type default)
			)
			(layer "B.SilkS")
		)
		(fp_line
			(start 1.143 -0.5588)
			(end 1.143 0.5588)
			(stroke
				(width 0.1)
				(type default)
			)
			(layer "B.SilkS")
		)
		(fp_line
			(start -1.143 0.5588)
			(end -1.143 -0.5588)
			(stroke
				(width 0.1)
				(type default)
			)
			(layer "B.SilkS")
		)
		(fp_line
			(start -1.143 -0.5588)
			(end 1.143 -0.5588)
			(stroke
				(width 0.1)
				(type default)
			)
			(layer "B.SilkS")
		)
		(fp_poly
			(pts
				(xy 1.143 0.5588) (xy -1.143 0.5588) (xy -1.143 -0.5588) (xy 1.143 -0.5588)
			)
			(stroke
				(width 0)
				(type default)
			)
			(fill no)
			(layer "B.CrtYd")
		)
		(fp_line
			(start 0.508 0.3048)
			(end -0.508 0.3048)
			(stroke
				(width 0.1)
				(type default)
			)
			(layer "B.Fab")
		)
		(fp_line
			(start 0.508 -0.3048)
			(end 0.508 0.3048)
			(stroke
				(width 0.1)
				(type default)
			)
			(layer "B.Fab")
		)
		(fp_line
			(start -0.508 0.3048)
			(end -0.508 -0.3048)
			(stroke
				(width 0.1)
				(type default)
			)
			(layer "B.Fab")
		)
		(fp_line
			(start -0.508 -0.3048)
			(end 0.508 -0.3048)
			(stroke
				(width 0.1)
				(type default)
			)
			(layer "B.Fab")
		)
		(pad "1" smd rect
			(at 0.5334 0)
			(size 0.7112 0.6096)
			(layers "B.Cu" "B.Mask" "B.Paste")
			(net "R_FT4232_TDO")
		)
		(pad "2" smd rect
			(at -0.5334 0)
			(size 0.7112 0.6096)
			(layers "B.Cu" "B.Mask" "B.Paste")
			(net "FT4232_TDO_MISO")
		)
		(zone
			(layer "B.Cu")
			(hatch none 0.5)
			(connect_pads
				(clearance 0)
			)
			(min_thickness 0.25)
			(keepout
				(tracks allowed)
				(vias not_allowed)
				(pads allowed)
				(copperpour not_allowed)
				(footprints allowed)
			)
			(placement
				(enabled no)
				(sheetname "")
			)
			(fill
				(thermal_gap 0.5)
				(thermal_bridge_width 0.5)
				(island_removal_mode 0)
			)
			(polygon
				(pts
					(xy 22.5298 -89.2048) (xy 22.5298 -88.5952) (xy 22.6822 -88.5952) (xy 22.6822 -89.2048)
				)
			)
		)
		(zone
			(layer "B.Cu")
			(hatch none 0.5)
			(connect_pads
				(clearance 0)
			)
			(min_thickness 0.25)
			(keepout
				(tracks not_allowed)
				(vias allowed)
				(pads allowed)
				(copperpour not_allowed)
				(footprints allowed)
			)
			(placement
				(enabled no)
				(sheetname "")
			)
			(fill
				(thermal_gap 0.5)
				(thermal_bridge_width 0.5)
				(island_removal_mode 0)
			)
			(polygon
				(pts
					(xy 22.5298 -89.2048) (xy 22.5298 -88.5952) (xy 22.6822 -88.5952) (xy 22.6822 -89.2048)
				)
			)
		)
	)
	(footprint ""
		(layer "B.Cu")
		(at 64.516 -58.039 -90)
		(property "Reference" "R100"
			(at 5.969 -0.34163 270)
			(unlocked yes)
			(layer "B.SilkS")
			(effects
				(font
					(size 0.7874 0.5842)
					(thickness 0.1524)
				)
				(justify mirror)
			)
		)
		(property "Value" "VAL*"
			(at -0.02032 2.13233 270)
			(unlocked yes)
			(layer "B.Fab")
			(hide yes)
			(effects
				(font
					(size 0.7874 0.5842)
					(thickness 0.1524)
				)
				(justify mirror)
			)
		)
		(property "Tolerance" "TOL*"
			(at -0.044704 3.05435 270)
			(unlocked yes)
			(layer "Cmts.User")
			(hide yes)
			(effects
				(font
					(size 0.7874 0.5842)
					(thickness 0.1524)
				)
				(justify mirror)
			)
		)
		(property "User Part Number" "PARTNUM*"
			(at -0.02032 4.024884 270)
			(unlocked yes)
			(layer "Cmts.User")
			(hide yes)
			(effects
				(font
					(size 0.7874 0.5842)
					(thickness 0.1524)
				)
				(justify mirror)
			)
		)
		(property "Device Type" "RESISTOR-G155-133R0-01,33OHM,1%"
			(at -0.008382 1.210564 270)
			(unlocked yes)
			(layer "B.Fab")
			(hide yes)
			(effects
				(font
					(size 0.7874 0.5842)
					(thickness 0.1524)
				)
				(justify mirror)
			)
		)
		(duplicate_pad_numbers_are_jumpers no)
		(fp_line
			(start -1.143 0.5588)
			(end -1.143 -0.5588)
			(stroke
				(width 0.1)
				(type default)
			)
			(layer "B.SilkS")
		)
		(fp_line
			(start 1.143 0.5588)
			(end -1.143 0.5588)
			(stroke
				(width 0.1)
				(type default)
			)
			(layer "B.SilkS")
		)
		(fp_line
			(start -1.143 -0.5588)
			(end 1.143 -0.5588)
			(stroke
				(width 0.1)
				(type default)
			)
			(layer "B.SilkS")
		)
		(fp_line
			(start 1.143 -0.5588)
			(end 1.143 0.5588)
			(stroke
				(width 0.1)
				(type default)
			)
			(layer "B.SilkS")
		)
		(fp_rect
			(start -1.143 -0.5588)
			(end 1.143 0.5588)
			(stroke
				(width 0)
				(type default)
			)
			(fill no)
			(layer "B.CrtYd")
		)
		(fp_line
			(start -0.508 0.3048)
			(end -0.508 -0.3048)
			(stroke
				(width 0.1)
				(type default)
			)
			(layer "B.Fab")
		)
		(fp_line
			(start 0.508 0.3048)
			(end -0.508 0.3048)
			(stroke
				(width 0.1)
				(type default)
			)
			(layer "B.Fab")
		)
		(fp_line
			(start -0.508 -0.3048)
			(end 0.508 -0.3048)
			(stroke
				(width 0.1)
				(type default)
			)
			(layer "B.Fab")
		)
		(fp_line
			(start 0.508 -0.3048)
			(end 0.508 0.3048)
			(stroke
				(width 0.1)
				(type default)
			)
			(layer "B.Fab")
		)
		(pad "1" smd rect
			(at 0.5334 0 90)
			(size 0.7112 0.6096)
			(layers "B.Cu" "B.Mask" "B.Paste")
			(net "FPGA_OUT_MACUSBPOWER_EN")
		)
		(pad "2" smd rect
			(at -0.5334 0 90)
			(size 0.7112 0.6096)
			(layers "B.Cu" "B.Mask" "B.Paste")
			(net "USB_PWR_EN")
		)
		(zone
			(layer "B.Cu")
			(hatch none 0.5)
			(connect_pads
				(clearance 0)
			)
			(min_thickness 0.25)
			(keepout
				(tracks allowed)
				(vias not_allowed)
				(pads allowed)
				(copperpour not_allowed)
				(footprints allowed)
			)
			(placement
				(enabled no)
				(sheetname "")
			)
			(fill
				(thermal_gap 0.5)
				(thermal_bridge_width 0.5)
				(island_removal_mode 0)
			)
			(polygon
				(pts
					(xy 64.8208 -58.1152) (xy 64.2112 -58.1152) (xy 64.2112 -57.9628) (xy 64.8208 -57.9628)
				)
			)
		)
	)
	(footprint ""
		(layer "B.Cu")
		(at 5.588 -74.295 180)
		(property "Reference" "R335"
			(at 2.921 0.34163 0)
			(unlocked yes)
			(layer "B.SilkS")
			(effects
				(font
					(size 0.7874 0.5842)
					(thickness 0.1524)
				)
				(justify mirror)
			)
		)
		(property "Value" "VAL*"
			(at -0.02032 2.13233 180)
			(unlocked yes)
			(layer "B.Fab")
			(hide yes)
			(effects
				(font
					(size 0.7874 0.5842)
					(thickness 0.1524)
				)
				(justify mirror)
			)
		)
		(property "Tolerance" "TOL*"
			(at -0.044704 3.05435 180)
			(unlocked yes)
			(layer "Cmts.User")
			(hide yes)
			(effects
				(font
					(size 0.7874 0.5842)
					(thickness 0.1524)
				)
				(justify mirror)
			)
		)
		(property "User Part Number" "PARTNUM*"
			(at -0.02032 4.024884 180)
			(unlocked yes)
			(layer "Cmts.User")
			(hide yes)
			(effects
				(font
					(size 0.7874 0.5842)
					(thickness 0.1524)
				)
				(justify mirror)
			)
		)
		(property "Device Type" "RESISTOR-G155-14701-01,4.7KOHMA"
			(at -0.008382 1.210564 180)
			(unlocked yes)
			(layer "B.Fab")
			(hide yes)
			(effects
				(font
					(size 0.7874 0.5842)
					(thickness 0.1524)
				)
				(justify mirror)
			)
		)
		(duplicate_pad_numbers_are_jumpers no)
		(fp_line
			(start 1.143 0.5588)
			(end -1.143 0.5588)
			(stroke
				(width 0.1)
				(type default)
			)
			(layer "B.SilkS")
		)
		(fp_line
			(start 1.143 -0.5588)
			(end 1.143 0.5588)
			(stroke
				(width 0.1)
				(type default)
			)
			(layer "B.SilkS")
		)
		(fp_line
			(start -1.143 0.5588)
			(end -1.143 -0.5588)
			(stroke
				(width 0.1)
				(type default)
			)
			(layer "B.SilkS")
		)
		(fp_line
			(start -1.143 -0.5588)
			(end 1.143 -0.5588)
			(stroke
				(width 0.1)
				(type default)
			)
			(layer "B.SilkS")
		)
		(fp_rect
			(start -1.143 0.5588)
			(end 1.143 -0.5588)
			(stroke
				(width 0)
				(type default)
			)
			(fill no)
			(layer "B.CrtYd")
		)
		(fp_line
			(start 0.508 0.3048)
			(end -0.508 0.3048)
			(stroke
				(width 0.1)
				(type default)
			)
			(layer "B.Fab")
		)
		(fp_line
			(start 0.508 -0.3048)
			(end 0.508 0.3048)
			(stroke
				(width 0.1)
				(type default)
			)
			(layer "B.Fab")
		)
		(fp_line
			(start -0.508 0.3048)
			(end -0.508 -0.3048)
			(stroke
				(width 0.1)
				(type default)
			)
			(layer "B.Fab")
		)
		(fp_line
			(start -0.508 -0.3048)
			(end 0.508 -0.3048)
			(stroke
				(width 0.1)
				(type default)
			)
			(layer "B.Fab")
		)
		(pad "1" smd rect
			(at 0.5334 0)
			(size 0.7112 0.6096)
			(layers "B.Cu" "B.Mask" "B.Paste")
			(net "XP3R3V_FPGA")
		)
		(pad "2" smd rect
			(at -0.5334 0)
			(size 0.7112 0.6096)
			(layers "B.Cu" "B.Mask" "B.Paste")
			(net "UNNAMED_6_LM75BDPTSSOP8_I34_A1")
		)
		(zone
			(layer "B.Cu")
			(hatch none 0.5)
			(connect_pads
				(clearance 0)
			)
			(min_thickness 0.25)
			(keepout
				(tracks allowed)
				(vias not_allowed)
				(pads allowed)
				(copperpour not_allowed)
				(footprints allowed)
			)
			(placement
				(enabled no)
				(sheetname "")
			)
			(fill
				(thermal_gap 0.5)
				(thermal_bridge_width 0.5)
				(island_removal_mode 0)
			)
			(polygon
				(pts
					(xy 5.6642 -74.5998) (xy 5.5118 -74.5998) (xy 5.5118 -73.9902) (xy 5.6642 -73.9902)
				)
			)
		)
	)
	(footprint ""
		(layer "B.Cu")
		(at 87.376 -57.277 180)
		(property "Reference" "R74"
			(at -1.778 -3.08737 0)
			(unlocked yes)
			(layer "B.SilkS")
			(effects
				(font
					(size 0.7874 0.5842)
					(thickness 0.1524)
				)
				(justify mirror)
			)
		)
		(property "Value" "VAL*"
			(at -0.02032 2.13233 180)
			(unlocked yes)
			(layer "B.Fab")
			(hide yes)
			(effects
				(font
					(size 0.7874 0.5842)
					(thickness 0.1524)
				)
				(justify mirror)
			)
		)
		(property "Device Type" "RESISTOR-G155-14701-01,4.7KOHMA"
			(at -0.008382 1.210564 180)
			(unlocked yes)
			(layer "B.Fab")
			(hide yes)
			(effects
				(font
					(size 0.7874 0.5842)
					(thickness 0.1524)
				)
				(justify mirror)
			)
		)
		(property "User Part Number" "PARTNUM*"
			(at -0.02032 4.024884 180)
			(unlocked yes)
			(layer "Cmts.User")
			(hide yes)
			(effects
				(font
					(size 0.7874 0.5842)
					(thickness 0.1524)
				)
				(justify mirror)
			)
		)
		(property "Tolerance" "TOL*"
			(at -0.044704 3.05435 180)
			(unlocked yes)
			(layer "Cmts.User")
			(hide yes)
			(effects
				(font
					(size 0.7874 0.5842)
					(thickness 0.1524)
				)
				(justify mirror)
			)
		)
		(duplicate_pad_numbers_are_jumpers no)
		(fp_line
			(start 1.143 0.5588)
			(end -1.143 0.5588)
			(stroke
				(width 0.1)
				(type default)
			)
			(layer "B.SilkS")
		)
		(fp_line
			(start 1.143 -0.5588)
			(end 1.143 0.5588)
			(stroke
				(width 0.1)
				(type default)
			)
			(layer "B.SilkS")
		)
		(fp_line
			(start -1.143 0.5588)
			(end -1.143 -0.5588)
			(stroke
				(width 0.1)
				(type default)
			)
			(layer "B.SilkS")
		)
		(fp_line
			(start -1.143 -0.5588)
			(end 1.143 -0.5588)
			(stroke
				(width 0.1)
				(type default)
			)
			(layer "B.SilkS")
		)
		(fp_rect
			(start -1.143 -0.5588)
			(end 1.143 0.5588)
			(stroke
				(width 0)
				(type default)
			)
			(fill no)
			(layer "B.CrtYd")
		)
		(fp_line
			(start 0.508 0.3048)
			(end -0.508 0.3048)
			(stroke
				(width 0.1)
				(type default)
			)
			(layer "B.Fab")
		)
		(fp_line
			(start 0.508 -0.3048)
			(end 0.508 0.3048)
			(stroke
				(width 0.1)
				(type default)
			)
			(layer "B.Fab")
		)
		(fp_line
			(start -0.508 0.3048)
			(end -0.508 -0.3048)
			(stroke
				(width 0.1)
				(type default)
			)
			(layer "B.Fab")
		)
		(fp_line
			(start -0.508 -0.3048)
			(end 0.508 -0.3048)
			(stroke
				(width 0.1)
				(type default)
			)
			(layer "B.Fab")
		)
		(pad "1" smd rect
			(at 0.5334 0)
			(size 0.7112 0.6096)
			(layers "B.Cu" "B.Mask" "B.Paste")
			(net "XP3R3V_FPGA")
		)
		(pad "2" smd rect
			(at -0.5334 0)
			(size 0.7112 0.6096)
			(layers "B.Cu" "B.Mask" "B.Paste")
			(net "BNO080_I2C_SDA")
		)
		(zone
			(layer "B.Cu")
			(hatch none 0.5)
			(connect_pads
				(clearance 0)
			)
			(min_thickness 0.25)
			(keepout
				(tracks allowed)
				(vias not_allowed)
				(pads allowed)
				(copperpour not_allowed)
				(footprints allowed)
			)
			(placement
				(enabled no)
				(sheetname "")
			)
			(fill
				(thermal_gap 0.5)
				(thermal_bridge_width 0.5)
				(island_removal_mode 0)
			)
			(polygon
				(pts
					(xy 87.4522 -56.9722) (xy 87.4522 -57.5818) (xy 87.2998 -57.5818) (xy 87.2998 -56.9722)
				)
			)
		)
	)
)
